# S9S_MB_2U (Grand Teton) — schematic netlist excerpt (pin names and nets, part order shuffled) for the footprints in the layout excerpt that follows; sources: Cadence DE-HDL packaged netlist, KiCad conversion of 03242023_DA0F0TMBIJ0_F0T_Motherboard_J_brd_V01_OCP.brd

R2910  Q_RES  100K 1% EMPTY  pkg 0402LF  page 149 : A = P3V3_AUX ; B = FM_SWB_PWR_EN_R
R3871  Q_RES  0 5% EMPTY  pkg 0402LF  page 157 : A = P12V_OCP_IMON_1 ; B = P12V_OCP_SFF_ISENSE_MPS_MAM
H23  HOLE  EMPTY  pkg TH  page 311 : \1\ = NC

(kicad_pcb
	(version 20260206)
	(generator "pcbnew")
	(generator_version "10.0")
	(general
		(thickness 1.6)
		(legacy_teardrops no)
	)
	(paper "A4")
	(title_block
		(title "03242023_DA0F0TMBIJ0_F0T_Motherboard_J_brd_V01_OCP.brd")
		(comment 1 "Grand Teton / footprints 759-761 of 6105")
	)
	(layers
		(0 "F.Cu" signal "TOP")
		(4 "In1.Cu" signal "GND")
		(6 "In2.Cu" signal "IN1")
		(8 "In3.Cu" signal "GND1")
		(10 "In4.Cu" signal "IN2")
		(12 "In5.Cu" signal "GND2")
		(14 "In6.Cu" signal "IN3")
		(16 "In7.Cu" signal "GND3")
		(18 "In8.Cu" signal "VCC")
		(20 "In9.Cu" signal "VCC1")
		(22 "In10.Cu" signal "GND4")
		(24 "In11.Cu" signal "IN4")
		(26 "In12.Cu" signal "GND5")
		(28 "In13.Cu" signal "IN5")
		(30 "In14.Cu" signal "GND6")
		(32 "In15.Cu" signal "IN6")
		(34 "In16.Cu" signal "GND7")
		(2 "B.Cu" signal "BOTTOM")
		(9 "F.Adhes" user "F.Adhesive")
		(11 "B.Adhes" user "B.Adhesive")
		(13 "F.Paste" user "Package Geometry/Pastemask Top")
		(15 "B.Paste" user "Package Geometry/Pastemask Bottom")
		(5 "F.SilkS" user "Ref Des/Silkscreen Top")
		(7 "B.SilkS" user "Ref Des/Silkscreen Bottom")
		(1 "F.Mask" user "Board Geometry/Soldermask Top")
		(3 "B.Mask" user "Board Geometry/Soldermask Bottom")
		(17 "Dwgs.User" user "User.Drawings")
		(19 "Cmts.User" user "User.Comments")
		(21 "Eco1.User" user "User.Eco1")
		(23 "Eco2.User" user "User.Eco2")
		(25 "Edge.Cuts" user "Board Geometry/Outline")
		(27 "Margin" user)
		(31 "F.CrtYd" user "Package Geometry/Place Bound Top")
		(29 "B.CrtYd" user "Package Geometry/Place Bound Bottom")
		(35 "F.Fab" user "Ref Des/Assembly Top")
		(33 "B.Fab" user "Ref Des/Assembly Bottom")
	)
	(footprint ""
		(layer "F.Cu")
		(at 336.86496 -206.024734)
		(property "Reference" "H23"
			(at -1.58496 4.537456 0)
			(unlocked yes)
			(layer "F.SilkS")
			(effects
				(font
					(size 0.7874 0.5842)
					(thickness 0.1524)
				)
				(justify left)
			)
		)
		(property "Value" ""
			(at 0 0 0)
			(layer "F.Fab")
			(effects
				(font
					(size 1.27 1.27)
				)
			)
		)
		(duplicate_pad_numbers_are_jumpers no)
		(fp_circle
			(center 0 0)
			(end 2.5273 0)
			(stroke
				(width 0.1524)
				(type default)
			)
			(fill no)
			(layer "F.SilkS")
		)
		(fp_circle
			(center 0 0)
			(end 2.5273 0)
			(stroke
				(width 0.1524)
				(type default)
			)
			(fill no)
			(layer "B.SilkS")
		)
		(fp_circle
			(center 0 0)
			(end 2.5273 0)
			(stroke
				(width 0.1)
				(type default)
			)
			(fill no)
			(layer "B.Fab")
		)
		(fp_circle
			(center 0 0)
			(end 2.5273 0)
			(stroke
				(width 0.1)
				(type default)
			)
			(fill no)
			(layer "F.Fab")
		)
		(pad "" np_thru_hole circle
			(at 0 0)
			(size 3.429 3.429)
			(drill 3.429)
			(layers "*.Cu" "*.Mask")
			(clearance 0.381)
			(thermal_gap 0.381)
		)
	)
	(footprint ""
		(layer "F.Cu")
		(at 437.240172 -32.173418 90)
		(property "Reference" "R3871"
			(at 0 0 90)
			(layer "F.SilkS")
			(hide yes)
			(effects
				(font
					(size 1.27 1.27)
				)
			)
		)
		(property "Value" ""
			(at 0 0 90)
			(layer "F.Fab")
			(effects
				(font
					(size 1.27 1.27)
				)
			)
		)
		(duplicate_pad_numbers_are_jumpers no)
		(fp_line
			(start 0.7874 -0.4064)
			(end 0.7874 0.4064)
			(stroke
				(width 0.1524)
				(type default)
			)
			(layer "F.SilkS")
		)
		(fp_line
			(start -0.7874 -0.4064)
			(end 0.7874 -0.4064)
			(stroke
				(width 0.1524)
				(type default)
			)
			(layer "F.SilkS")
		)
		(fp_line
			(start 0.7874 0.4064)
			(end -0.7874 0.4064)
			(stroke
				(width 0.1524)
				(type default)
			)
			(layer "F.SilkS")
		)
		(fp_line
			(start -0.7874 0.4064)
			(end -0.7874 -0.4064)
			(stroke
				(width 0.1524)
				(type default)
			)
			(layer "F.SilkS")
		)
		(fp_line
			(start -0.12065 -0.305054)
			(end -0.12065 -0.2794)
			(stroke
				(width 0.1)
				(type default)
			)
			(layer "F.Fab")
		)
		(fp_line
			(start -0.67945 -0.305054)
			(end -0.12065 -0.305054)
			(stroke
				(width 0.1)
				(type default)
			)
			(layer "F.Fab")
		)
		(fp_line
			(start 0.67945 -0.3048)
			(end 0.67945 0.3048)
			(stroke
				(width 0.1)
				(type default)
			)
			(layer "F.Fab")
		)
		(fp_line
			(start 0.12065 -0.3048)
			(end 0.67945 -0.3048)
			(stroke
				(width 0.1)
				(type default)
			)
			(layer "F.Fab")
		)
		(fp_line
			(start 0.12065 -0.2794)
			(end 0.12065 -0.3048)
			(stroke
				(width 0.1)
				(type default)
			)
			(layer "F.Fab")
		)
		(fp_line
			(start -0.12065 -0.2794)
			(end 0.12065 -0.2794)
			(stroke
				(width 0.1)
				(type default)
			)
			(layer "F.Fab")
		)
		(fp_line
			(start 0.120396 0.2794)
			(end -0.12065 0.2794)
			(stroke
				(width 0.1)
				(type default)
			)
			(layer "F.Fab")
		)
		(fp_line
			(start -0.12065 0.2794)
			(end -0.12065 0.3048)
			(stroke
				(width 0.1)
				(type default)
			)
			(layer "F.Fab")
		)
		(fp_line
			(start 0.67945 0.3048)
			(end 0.120396 0.3048)
			(stroke
				(width 0.1)
				(type default)
			)
			(layer "F.Fab")
		)
		(fp_line
			(start 0.120396 0.3048)
			(end 0.120396 0.2794)
			(stroke
				(width 0.1)
				(type default)
			)
			(layer "F.Fab")
		)
		(fp_line
			(start -0.12065 0.3048)
			(end -0.67945 0.3048)
			(stroke
				(width 0.1)
				(type default)
			)
			(layer "F.Fab")
		)
		(fp_line
			(start -0.67945 0.3048)
			(end -0.67945 -0.305054)
			(stroke
				(width 0.1)
				(type default)
			)
			(layer "F.Fab")
		)
		(pad "1" smd circle
			(at -0.40005 0 90)
			(size 0 0)
			(layers "F.Cu" "F.Mask" "F.Paste")
			(net "P12V_OCP_IMON_1")
		)
		(pad "2" smd circle
			(at 0.40005 0 90)
			(size 0 0)
			(layers "F.Cu" "F.Mask" "F.Paste")
			(net "P12V_OCP_SFF_ISENSE_MPS_MAM")
		)
	)
	(footprint ""
		(layer "F.Cu")
		(at 22.91588 -430.367948)
		(property "Reference" "R2910"
			(at 0 0 0)
			(layer "F.SilkS")
			(hide yes)
			(effects
				(font
					(size 1.27 1.27)
				)
			)
		)
		(property "Value" ""
			(at 0 0 0)
			(layer "F.Fab")
			(effects
				(font
					(size 1.27 1.27)
				)
			)
		)
		(duplicate_pad_numbers_are_jumpers no)
		(fp_line
			(start -0.7874 -0.4064)
			(end 0.7874 -0.4064)
			(stroke
				(width 0.1524)
				(type default)
			)
			(layer "F.SilkS")
		)
		(fp_line
			(start -0.7874 0.4064)
			(end -0.7874 -0.4064)
			(stroke
				(width 0.1524)
				(type default)
			)
			(layer "F.SilkS")
		)
		(fp_line
			(start 0.7874 -0.4064)
			(end 0.7874 0.4064)
			(stroke
				(width 0.1524)
				(type default)
			)
			(layer "F.SilkS")
		)
		(fp_line
			(start 0.7874 0.4064)
			(end -0.7874 0.4064)
			(stroke
				(width 0.1524)
				(type default)
			)
			(layer "F.SilkS")
		)
		(fp_line
			(start -0.67945 -0.305054)
			(end -0.12065 -0.305054)
			(stroke
				(width 0.1)
				(type default)
			)
			(layer "F.Fab")
		)
		(fp_line
			(start -0.67945 0.3048)
			(end -0.67945 -0.305054)
			(stroke
				(width 0.1)
				(type default)
			)
			(layer "F.Fab")
		)
		(fp_line
			(start -0.12065 -0.305054)
			(end -0.12065 -0.2794)
			(stroke
				(width 0.1)
				(type default)
			)
			(layer "F.Fab")
		)
		(fp_line
			(start -0.12065 -0.2794)
			(end 0.12065 -0.2794)
			(stroke
				(width 0.1)
				(type default)
			)
			(layer "F.Fab")
		)
		(fp_line
			(start -0.12065 0.2794)
			(end -0.12065 0.3048)
			(stroke
				(width 0.1)
				(type default)
			)
			(layer "F.Fab")
		)
		(fp_line
			(start -0.12065 0.3048)
			(end -0.67945 0.3048)
			(stroke
				(width 0.1)
				(type default)
			)
			(layer "F.Fab")
		)
		(fp_line
			(start 0.120396 0.2794)
			(end -0.12065 0.2794)
			(stroke
				(width 0.1)
				(type default)
			)
			(layer "F.Fab")
		)
		(fp_line
			(start 0.120396 0.3048)
			(end 0.120396 0.2794)
			(stroke
				(width 0.1)
				(type default)
			)
			(layer "F.Fab")
		)
		(fp_line
			(start 0.12065 -0.3048)
			(end 0.67945 -0.3048)
			(stroke
				(width 0.1)
				(type default)
			)
			(layer "F.Fab")
		)
		(fp_line
			(start 0.12065 -0.2794)
			(end 0.12065 -0.3048)
			(stroke
				(width 0.1)
				(type default)
			)
			(layer "F.Fab")
		)
		(fp_line
			(start 0.67945 -0.3048)
			(end 0.67945 0.3048)
			(stroke
				(width 0.1)
				(type default)
			)
			(layer "F.Fab")
		)
		(fp_line
			(start 0.67945 0.3048)
			(end 0.120396 0.3048)
			(stroke
				(width 0.1)
				(type default)
			)
			(layer "F.Fab")
		)
		(pad "1" smd circle
			(at -0.40005 0)
			(size 0 0)
			(layers "F.Cu" "F.Mask" "F.Paste")
			(net "P3V3_AUX")
		)
		(pad "2" smd circle
			(at 0.40005 0)
			(size 0 0)
			(layers "F.Cu" "F.Mask" "F.Paste")
			(net "FM_SWB_PWR_EN_R")
		)
	)
)
